(kicad_pcb
	(version 20260206)
	(generator "pcbnew")
	(generator_version "10.0")
	(general
		(thickness 1.6)
		(legacy_teardrops no)
	)
	(paper "A4")
	(title_block
		(title "pdpb — Lightning_PDPB_BRD.brd")
		(comment 1 "Lightning (Wiwynn / Facebook NVMe JBOF) / footprints 70-71 of 1140")
	)
	(layers
		(0 "F.Cu" signal "TOP")
		(4 "In1.Cu" signal "L2GND")
		(6 "In2.Cu" signal "L3")
		(8 "In3.Cu" signal "L4VCC")
		(10 "In4.Cu" signal "L5VCC")
		(12 "In5.Cu" signal "L6")
		(14 "In6.Cu" signal "L7GND")
		(2 "B.Cu" signal "BOTTOM")
		(9 "F.Adhes" user "F.Adhesive")
		(11 "B.Adhes" user "B.Adhesive")
		(13 "F.Paste" user "Package Geometry/Pastemask Top")
		(15 "B.Paste" user "Package Geometry/Pastemask Bottom")
		(5 "F.SilkS" user "Ref Des/Silkscreen Top")
		(7 "B.SilkS" user "Ref Des/Silkscreen Bottom")
		(1 "F.Mask" user "Board Geometry/Soldermask Top")
		(3 "B.Mask" user "Board Geometry/Soldermask Bottom")
		(17 "Dwgs.User" user "User.Drawings")
		(19 "Cmts.User" user "User.Comments")
		(21 "Eco1.User" user "User.Eco1")
		(23 "Eco2.User" user "User.Eco2")
		(25 "Edge.Cuts" user "Board Geometry/Outline")
		(27 "Margin" user)
		(31 "F.CrtYd" user "Package Geometry/Place Bound Top")
		(29 "B.CrtYd" user "Package Geometry/Place Bound Bottom")
		(35 "F.Fab" user "Ref Des/Assembly Top")
		(33 "B.Fab" user "Ref Des/Assembly Bottom")
	)
	(footprint ""
		(layer "F.Cu")
		(at 93.98 -305.181 90)
		(property "Reference" "EU2"
			(at 0 0 90)
			(layer "F.SilkS")
			(hide yes)
			(effects
				(font
					(size 1.27 1.27)
				)
			)
		)
		(property "Value" "9ZXL1231AKLFT-GP"
			(at -6.5278 -7.2009 90)
			(unlocked yes)
			(layer "F.Fab")
			(hide yes)
			(effects
				(font
					(size 1.016 1.016)
					(thickness 0.1524)
				)
			)
		)
		(property "Device Type" "QFN64G9-G6D25H40"
			(at -6.5278 -8.7249 90)
			(unlocked yes)
			(layer "F.Fab")
			(hide yes)
			(effects
				(font
					(size 1.016 1.016)
					(thickness 0.1524)
				)
			)
		)
		(duplicate_pad_numbers_are_jumpers no)
		(fp_line
			(start 1.7526 -5.71881)
			(end 1.7526 -5.21081)
			(stroke
				(width 0.1524)
				(type default)
			)
			(layer "F.SilkS")
		)
		(fp_line
			(start -3.2639 -5.71881)
			(end -3.2639 -5.21081)
			(stroke
				(width 0.1524)
				(type default)
			)
			(layer "F.SilkS")
		)
		(fp_line
			(start -3.9878 -5.5118)
			(end -5.5118 -5.5118)
			(stroke
				(width 0.1524)
				(type default)
			)
			(layer "F.SilkS")
		)
		(fp_line
			(start -5.5118 -5.5118)
			(end -5.5118 -3.9243)
			(stroke
				(width 0.1524)
				(type default)
			)
			(layer "F.SilkS")
		)
		(fp_line
			(start -0.74041 -5.21081)
			(end -0.74041 -5.97281)
			(stroke
				(width 0.1524)
				(type default)
			)
			(layer "F.SilkS")
		)
		(fp_line
			(start -5.97281 -2.2606)
			(end -5.21081 -2.2606)
			(stroke
				(width 0.1524)
				(type default)
			)
			(layer "F.SilkS")
		)
		(fp_line
			(start 5.21081 -1.778)
			(end 5.97281 -1.778)
			(stroke
				(width 0.1524)
				(type default)
			)
			(layer "F.SilkS")
		)
		(fp_line
			(start -5.21081 0.254)
			(end -5.71881 0.254)
			(stroke
				(width 0.1524)
				(type default)
			)
			(layer "F.SilkS")
		)
		(fp_line
			(start 5.71881 0.7112)
			(end 5.21081 0.7112)
			(stroke
				(width 0.1524)
				(type default)
			)
			(layer "F.SilkS")
		)
		(fp_line
			(start -5.97281 2.7432)
			(end -5.21081 2.7432)
			(stroke
				(width 0.1524)
				(type default)
			)
			(layer "F.SilkS")
		)
		(fp_line
			(start 5.21081 3.22961)
			(end 5.97281 3.22961)
			(stroke
				(width 0.1524)
				(type default)
			)
			(layer "F.SilkS")
		)
		(fp_line
			(start -5.4991 4.1148)
			(end -5.4991 5.5118)
			(stroke
				(width 0.1524)
				(type default)
			)
			(layer "F.SilkS")
		)
		(fp_line
			(start 2.2352 5.21081)
			(end 2.2352 5.71881)
			(stroke
				(width 0.1524)
				(type default)
			)
			(layer "F.SilkS")
		)
		(fp_line
			(start -2.7432 5.21081)
			(end -2.7432 5.71881)
			(stroke
				(width 0.1524)
				(type default)
			)
			(layer "F.SilkS")
		)
		(fp_line
			(start 5.5118 5.4991)
			(end 5.5118 3.9878)
			(stroke
				(width 0.1524)
				(type default)
			)
			(layer "F.SilkS")
		)
		(fp_line
			(start 4.0767 5.4991)
			(end 5.5118 5.4991)
			(stroke
				(width 0.1524)
				(type default)
			)
			(layer "F.SilkS")
		)
		(fp_line
			(start -5.4991 5.5118)
			(end -4.2037 5.5118)
			(stroke
				(width 0.1524)
				(type default)
			)
			(layer "F.SilkS")
		)
		(fp_line
			(start -0.7366 5.97281)
			(end -0.7366 5.21081)
			(stroke
				(width 0.1524)
				(type default)
			)
			(layer "F.SilkS")
		)
		(fp_poly
			(pts
				(xy 5.405628 -4.161028) (xy 4.05511 -5.5118) (xy 5.405628 -5.5118)
			)
			(stroke
				(width 0)
				(type default)
			)
			(fill yes)
			(layer "F.SilkS")
		)
		(fp_rect
			(start -4.4958 4.4958)
			(end 4.4958 -4.4958)
			(stroke
				(width 0)
				(type default)
			)
			(fill no)
			(layer "F.CrtYd")
		)
		(fp_poly
			(pts
				(xy -5.5118 5.5118) (xy -5.5118 -5.5118) (xy 5.5118 -5.5118) (xy 5.5118 -0.5461) (xy 4.4958 -0.5461)
				(xy 4.4958 -4.4958) (xy -4.4958 -4.4958) (xy -4.4958 4.4958) (xy 4.4958 4.4958) (xy 4.4958 -0.5334)
				(xy 5.5118 -0.5334) (xy 5.5118 5.5118)
			)
			(stroke
				(width 0)
				(type default)
			)
			(fill no)
			(layer "F.CrtYd")
		)
		(fp_rect
			(start -5.5118 5.5118)
			(end 5.5118 -5.5118)
			(stroke
				(width 0)
				(type default)
			)
			(fill no)
			(layer "F.Fab")
		)
		(pad "1" smd rect
			(at 3.75031 -4.550918 90)
			(size 0.3048 0.9144)
			(layers "F.Cu" "F.Mask" "F.Paste")
			(net "VDDA_2")
		)
		(pad "2" smd rect
			(at 3.24993 -4.42341 90)
			(size 0.3048 1.1684)
			(layers "F.Cu" "F.Mask" "F.Paste")
			(net "GND")
		)
		(pad "3" smd rect
			(at 2.74955 -4.42341 90)
			(size 0.3048 1.1684)
			(layers "F.Cu" "F.Mask" "F.Paste")
			(net "Net_1329")
		)
		(pad "4" smd rect
			(at 2.25044 -4.42341 90)
			(size 0.3048 1.1684)
			(layers "F.Cu" "F.Mask" "F.Paste")
			(net "CLK_BUF_EU2_100M_133M#")
		)
		(pad "5" smd rect
			(at 1.75006 -4.42341 90)
			(size 0.3048 1.1684)
			(layers "F.Cu" "F.Mask" "F.Paste")
			(net "CLK_BUF_EU2_HIBW_BYPM_LOBW#")
		)
		(pad "6" smd rect
			(at 1.24968 -4.42341 90)
			(size 0.3048 1.1684)
			(layers "F.Cu" "F.Mask" "F.Paste")
			(net "P3V3_PG")
		)
		(pad "7" smd rect
			(at 0.75057 -4.42341 90)
			(size 0.3048 1.1684)
			(layers "F.Cu" "F.Mask" "F.Paste")
			(net "GND")
		)
		(pad "8" smd rect
			(at 0.25019 -4.42341 90)
			(size 0.3048 1.1684)
			(layers "F.Cu" "F.Mask" "F.Paste")
			(net "VDDR_2")
		)
		(pad "9" smd rect
			(at -0.25019 -4.42341 90)
			(size 0.3048 1.1684)
			(layers "F.Cu" "F.Mask" "F.Paste")
			(net "PE_100M_CLK3_P")
		)
		(pad "10" smd rect
			(at -0.75057 -4.42341 90)
			(size 0.3048 1.1684)
			(layers "F.Cu" "F.Mask" "F.Paste")
			(net "PE_100M_CLK3_N")
		)
		(pad "11" smd rect
			(at -1.24968 -4.42341 90)
			(size 0.3048 1.1684)
			(layers "F.Cu" "F.Mask" "F.Paste")
			(net "CLK_BUF_EU2_SMB_A0_TRI")
		)
		(pad "12" smd rect
			(at -1.75006 -4.42341 90)
			(size 0.3048 1.1684)
			(layers "F.Cu" "F.Mask" "F.Paste")
			(net "I2C_SDA_BUF_9_EU2_R")
		)
		(pad "13" smd rect
			(at -2.25044 -4.42341 90)
			(size 0.3048 1.1684)
			(layers "F.Cu" "F.Mask" "F.Paste")
			(net "I2C_SCL_BUF_9_EU2_R")
		)
		(pad "14" smd rect
			(at -2.74955 -4.42341 90)
			(size 0.3048 1.1684)
			(layers "F.Cu" "F.Mask" "F.Paste")
			(net "CLK_BUF_EU2_SMB_A1_TRI")
		)
		(pad "15" smd rect
			(at -3.24993 -4.42341 90)
			(size 0.3048 1.1684)
			(layers "F.Cu" "F.Mask" "F.Paste")
			(net "Net_1331")
		)
		(pad "16" smd rect
			(at -3.75031 -4.550918 90)
			(size 0.3048 0.9144)
			(layers "F.Cu" "F.Mask" "F.Paste")
			(net "Net_1330")
		)
		(pad "17" smd rect
			(at -4.550918 -3.75031 90)
			(size 0.9144 0.3048)
			(layers "F.Cu" "F.Mask" "F.Paste")
			(net "Net_315")
		)
		(pad "18" smd rect
			(at -4.42341 -3.24993 90)
			(size 1.1684 0.3048)
			(layers "F.Cu" "F.Mask" "F.Paste")
			(net "Net_314")
		)
		(pad "19" smd rect
			(at -4.42341 -2.74955 90)
			(size 1.1684 0.3048)
			(layers "F.Cu" "F.Mask" "F.Paste")
			(net "CLK_BUFFER_EU2_VOE_N")
		)
		(pad "20" smd rect
			(at -4.42341 -2.25044 90)
			(size 1.1684 0.3048)
			(layers "F.Cu" "F.Mask" "F.Paste")
			(net "CLK_BUFFER_EU2_VOE_N")
		)
		(pad "21" smd rect
			(at -4.42341 -1.75006 90)
			(size 1.1684 0.3048)
			(layers "F.Cu" "F.Mask" "F.Paste")
			(net "Net_313")
		)
		(pad "22" smd rect
			(at -4.42341 -1.24968 90)
			(size 1.1684 0.3048)
			(layers "F.Cu" "F.Mask" "F.Paste")
			(net "Net_312")
		)
		(pad "23" smd rect
			(at -4.42341 -0.75057 90)
			(size 1.1684 0.3048)
			(layers "F.Cu" "F.Mask" "F.Paste")
			(net "GND")
		)
		(pad "24" smd rect
			(at -4.42341 -0.25019 90)
			(size 1.1684 0.3048)
			(layers "F.Cu" "F.Mask" "F.Paste")
			(net "VDD_DIFF_2")
		)
		(pad "25" smd rect
			(at -4.42341 0.25019 90)
			(size 1.1684 0.3048)
			(layers "F.Cu" "F.Mask" "F.Paste")
			(net "VDD_IO_2")
		)
		(pad "26" smd rect
			(at -4.42341 0.75057 90)
			(size 1.1684 0.3048)
			(layers "F.Cu" "F.Mask" "F.Paste")
			(net "PE_CLK_100M_DR2_2_R_P")
		)
		(pad "27" smd rect
			(at -4.42341 1.24968 90)
			(size 1.1684 0.3048)
			(layers "F.Cu" "F.Mask" "F.Paste")
			(net "PE_CLK_100M_DR2_2_R_N")
		)
		(pad "28" smd rect
			(at -4.42341 1.75006 90)
			(size 1.1684 0.3048)
			(layers "F.Cu" "F.Mask" "F.Paste")
			(net "SSD_PRSNT2")
		)
		(pad "29" smd rect
			(at -4.42341 2.25044 90)
			(size 1.1684 0.3048)
			(layers "F.Cu" "F.Mask" "F.Paste")
			(net "SSD2_CLK0_OE_R_N")
		)
		(pad "30" smd rect
			(at -4.42341 2.74955 90)
			(size 1.1684 0.3048)
			(layers "F.Cu" "F.Mask" "F.Paste")
			(net "PE_CLK_100M_DR2_1_R_P")
		)
		(pad "31" smd rect
			(at -4.42341 3.24993 90)
			(size 1.1684 0.3048)
			(layers "F.Cu" "F.Mask" "F.Paste")
			(net "PE_CLK_100M_DR2_1_R_N")
		)
		(pad "32" smd rect
			(at -4.550918 3.75031 90)
			(size 0.9144 0.3048)
			(layers "F.Cu" "F.Mask" "F.Paste")
			(net "VDD_IO_2")
		)
		(pad "33" smd rect
			(at -3.75031 4.550918 90)
			(size 0.3048 0.9144)
			(layers "F.Cu" "F.Mask" "F.Paste")
			(net "GND")
		)
		(pad "34" smd rect
			(at -3.24993 4.42341 90)
			(size 0.3048 1.1684)
			(layers "F.Cu" "F.Mask" "F.Paste")
			(net "Net_327")
		)
		(pad "35" smd rect
			(at -2.74955 4.42341 90)
			(size 0.3048 1.1684)
			(layers "F.Cu" "F.Mask" "F.Paste")
			(net "Net_326")
		)
		(pad "36" smd rect
			(at -2.25044 4.42341 90)
			(size 0.3048 1.1684)
			(layers "F.Cu" "F.Mask" "F.Paste")
			(net "CLK_BUFFER_EU2_VOE_N")
		)
		(pad "37" smd rect
			(at -1.75006 4.42341 90)
			(size 0.3048 1.1684)
			(layers "F.Cu" "F.Mask" "F.Paste")
			(net "CLK_BUFFER_EU2_VOE_N")
		)
		(pad "38" smd rect
			(at -1.24968 4.42341 90)
			(size 0.3048 1.1684)
			(layers "F.Cu" "F.Mask" "F.Paste")
			(net "Net_325")
		)
		(pad "39" smd rect
			(at -0.75057 4.42341 90)
			(size 0.3048 1.1684)
			(layers "F.Cu" "F.Mask" "F.Paste")
			(net "Net_324")
		)
		(pad "40" smd rect
			(at -0.25019 4.42341 90)
			(size 0.3048 1.1684)
			(layers "F.Cu" "F.Mask" "F.Paste")
			(net "VDD_DIFF_2")
		)
		(pad "41" smd rect
			(at 0.25019 4.42341 90)
			(size 0.3048 1.1684)
			(layers "F.Cu" "F.Mask" "F.Paste")
			(net "GND")
		)
		(pad "42" smd rect
			(at 0.75057 4.42341 90)
			(size 0.3048 1.1684)
			(layers "F.Cu" "F.Mask" "F.Paste")
			(net "PE_CLK_100M_DR1_2_R_P")
		)
		(pad "43" smd rect
			(at 1.24968 4.42341 90)
			(size 0.3048 1.1684)
			(layers "F.Cu" "F.Mask" "F.Paste")
			(net "PE_CLK_100M_DR1_2_R_N")
		)
		(pad "44" smd rect
			(at 1.75006 4.42341 90)
			(size 0.3048 1.1684)
			(layers "F.Cu" "F.Mask" "F.Paste")
			(net "SSD_PRSNT1")
		)
		(pad "45" smd rect
			(at 2.25044 4.42341 90)
			(size 0.3048 1.1684)
			(layers "F.Cu" "F.Mask" "F.Paste")
			(net "SSD1_CLK0_OE_R_N")
		)
		(pad "46" smd rect
			(at 2.74955 4.42341 90)
			(size 0.3048 1.1684)
			(layers "F.Cu" "F.Mask" "F.Paste")
			(net "PE_CLK_100M_DR1_1_R_P")
		)
		(pad "47" smd rect
			(at 3.24993 4.42341 90)
			(size 0.3048 1.1684)
			(layers "F.Cu" "F.Mask" "F.Paste")
			(net "PE_CLK_100M_DR1_1_R_N")
		)
		(pad "48" smd rect
			(at 3.75031 4.550918 90)
			(size 0.3048 0.9144)
			(layers "F.Cu" "F.Mask" "F.Paste")
			(net "GND")
		)
		(pad "49" smd rect
			(at 4.550918 3.75031 90)
			(size 0.9144 0.3048)
			(layers "F.Cu" "F.Mask" "F.Paste")
			(net "VDD_IO_2")
		)
		(pad "50" smd rect
			(at 4.42341 3.24993 90)
			(size 1.1684 0.3048)
			(layers "F.Cu" "F.Mask" "F.Paste")
			(net "PE_CLK_100M_DR6_2_R_P")
		)
		(pad "51" smd rect
			(at 4.42341 2.74955 90)
			(size 1.1684 0.3048)
			(layers "F.Cu" "F.Mask" "F.Paste")
			(net "PE_CLK_100M_DR6_2_R_N")
		)
		(pad "52" smd rect
			(at 4.42341 2.25044 90)
			(size 1.1684 0.3048)
			(layers "F.Cu" "F.Mask" "F.Paste")
			(net "SSD_PRSNT6")
		)
		(pad "53" smd rect
			(at 4.42341 1.75006 90)
			(size 1.1684 0.3048)
			(layers "F.Cu" "F.Mask" "F.Paste")
			(net "SSD6_CLK0_OE_R_N")
		)
		(pad "54" smd rect
			(at 4.42341 1.24968 90)
			(size 1.1684 0.3048)
			(layers "F.Cu" "F.Mask" "F.Paste")
			(net "PE_CLK_100M_DR6_1_R_P")
		)
		(pad "55" smd rect
			(at 4.42341 0.75057 90)
			(size 1.1684 0.3048)
			(layers "F.Cu" "F.Mask" "F.Paste")
			(net "PE_CLK_100M_DR6_1_R_N")
		)
		(pad "56" smd rect
			(at 4.42341 0.25019 90)
			(size 1.1684 0.3048)
			(layers "F.Cu" "F.Mask" "F.Paste")
			(net "VDD_IO_2")
		)
		(pad "57" smd rect
			(at 4.42341 -0.25019 90)
			(size 1.1684 0.3048)
			(layers "F.Cu" "F.Mask" "F.Paste")
			(net "VDD_DIFF_2")
		)
		(pad "58" smd rect
			(at 4.42341 -0.75057 90)
			(size 1.1684 0.3048)
			(layers "F.Cu" "F.Mask" "F.Paste")
			(net "GND")
		)
		(pad "59" smd rect
			(at 4.42341 -1.24968 90)
			(size 1.1684 0.3048)
			(layers "F.Cu" "F.Mask" "F.Paste")
			(net "PE_CLK_100M_DR11_2_R_P")
		)
		(pad "60" smd rect
			(at 4.42341 -1.75006 90)
			(size 1.1684 0.3048)
			(layers "F.Cu" "F.Mask" "F.Paste")
			(net "PE_CLK_100M_DR11_2_R_N")
		)
		(pad "61" smd rect
			(at 4.42341 -2.25044 90)
			(size 1.1684 0.3048)
			(layers "F.Cu" "F.Mask" "F.Paste")
			(net "SSD_PRSNT11")
		)
		(pad "62" smd rect
			(at 4.42341 -2.74955 90)
			(size 1.1684 0.3048)
			(layers "F.Cu" "F.Mask" "F.Paste")
			(net "SSD11_CLK0_OE_R_N")
		)
		(pad "63" smd rect
			(at 4.42341 -3.24993 90)
			(size 1.1684 0.3048)
			(layers "F.Cu" "F.Mask" "F.Paste")
			(net "PE_CLK_100M_DR11_1_R_P")
		)
		(pad "64" smd rect
			(at 4.550918 -3.75031 90)
			(size 0.9144 0.3048)
			(layers "F.Cu" "F.Mask" "F.Paste")
			(net "PE_CLK_100M_DR11_1_R_N")
		)
		(pad "65" smd rect
			(at 0 0 90)
			(size 6.2484 6.2484)
			(layers "F.Cu" "F.Mask" "F.Paste")
			(net "GND")
		)
	)
	(footprint ""
		(layer "F.Cu")
		(at 251.587 -360.553)
		(property "Reference" "PC1291"
			(at 0 0 0)
			(layer "F.SilkS")
			(hide yes)
			(effects
				(font
					(size 1.27 1.27)
				)
			)
		)
		(property "Value" "SCD1U25V3KX-GP"
			(at 0 -2.8194 0)
			(unlocked yes)
			(layer "F.Fab")
			(hide yes)
			(effects
				(font
					(size 1.016 1.016)
					(thickness 0.1524)
				)
			)
		)
		(property "Device Type" "C603H36"
			(at 0 -4.3434 0)
			(unlocked yes)
			(layer "F.Fab")
			(hide yes)
			(effects
				(font
					(size 1.016 1.016)
					(thickness 0.1524)
				)
			)
		)
		(duplicate_pad_numbers_are_jumpers no)
		(fp_line
			(start 0.508 0)
			(end -0.508 0)
			(stroke
				(width 0.2032)
				(type default)
			)
			(layer "F.SilkS")
		)
		(fp_rect
			(start -0.5842 1.3335)
			(end 0.5842 -1.3335)
			(stroke
				(width 0)
				(type default)
			)
			(fill no)
			(layer "F.CrtYd")
		)
		(fp_rect
			(start -0.5842 1.3335)
			(end 0.5842 -1.3335)
			(stroke
				(width 0)
				(type default)
			)
			(fill no)
			(layer "F.Fab")
		)
		(pad "1" smd custom
			(at 0 -0.762)
			(size 0.2159 0.2159)
			(layers "F.Cu" "F.Mask" "F.Paste")
			(net "P12V")
			(options
				(clearance outline)
				(anchor circle)
			)
			(primitives
				(gr_poly
					(pts
						(arc
							(start -0.3302 -0.4318)
							(mid -0.402042 -0.402042)
							(end -0.4318 -0.3302)
						)
						(arc
							(start -0.4318 0.3302)
							(mid -0.402042 0.402042)
							(end -0.3302 0.4318)
						)
						(arc
							(start 0.3302 0.4318)
							(mid 0.402042 0.402042)
							(end 0.4318 0.3302)
						)
						(arc
							(start 0.4318 -0.3302)
							(mid 0.402042 -0.402042)
							(end 0.3302 -0.4318)
						)
					)
					(width 0)
					(fill yes)
				)
			)
		)
		(pad "2" smd custom
			(at 0 0.762)
			(size 0.2159 0.2159)
			(layers "F.Cu" "F.Mask" "F.Paste")
			(net "GND")
			(options
				(clearance outline)
				(anchor circle)
			)
			(primitives
				(gr_poly
					(pts
						(arc
							(start -0.3302 -0.4318)
							(mid -0.402042 -0.402042)
							(end -0.4318 -0.3302)
						)
						(arc
							(start -0.4318 0.3302)
							(mid -0.402042 0.402042)
							(end -0.3302 0.4318)
						)
						(arc
							(start 0.3302 0.4318)
							(mid 0.402042 0.402042)
							(end 0.4318 0.3302)
						)
						(arc
							(start 0.4318 -0.3302)
							(mid 0.402042 -0.402042)
							(end 0.3302 -0.4318)
						)
					)
					(width 0)
					(fill yes)
				)
			)
		)
	)
)
